(kicad_pcb
	(version 20241229)
	(generator "pcbnew")
	(generator_version "9.0")
	(general
		(thickness 1.6)
		(legacy_teardrops no)
	)
	(paper "A4")
	(title_block
		(title "environment-sensor")
		(comment 1 "footprints 18-24 of 109")
	)
	(layers
		(0 "F.Cu" signal)
		(4 "In1.Cu" signal)
		(6 "In2.Cu" signal)
		(2 "B.Cu" signal)
		(9 "F.Adhes" user "F.Adhesive")
		(11 "B.Adhes" user "B.Adhesive")
		(13 "F.Paste" user)
		(15 "B.Paste" user)
		(5 "F.SilkS" user "F.Silkscreen")
		(7 "B.SilkS" user "B.Silkscreen")
		(1 "F.Mask" user)
		(3 "B.Mask" user)
		(17 "Dwgs.User" user "User.Drawings")
		(19 "Cmts.User" user "User.Comments")
		(21 "Eco1.User" user "User.Eco1")
		(23 "Eco2.User" user "User.Eco2")
		(25 "Edge.Cuts" user)
		(27 "Margin" user)
		(31 "F.CrtYd" user "F.Courtyard")
		(29 "B.CrtYd" user "B.Courtyard")
		(35 "F.Fab" user)
		(33 "B.Fab" user)
	)
	(footprint "antmicro-footprints:Conn_JST_SH_1x4_SM04B-SRSS-TB-LF-SN"
		(layer "F.Cu")
		(at 207.2755 129.25 90)
		(property "Reference" "J2"
			(at 2.15 -2.3255 90)
			(layer "F.SilkS")
			(effects
				(font
					(size 0.7 0.7)
					(thickness 0.15)
				)
				(justify left bottom)
			)
		)
		(property "Value" "JST_SH_1x4_SM04B-SRSS-TB-LF-SN"
			(at 0 3.9 90)
			(layer "F.Fab")
			(effects
				(font
					(size 0.7 0.7)
					(thickness 0.15)
				)
				(justify left bottom)
			)
		)
		(property "Description" "Pin Header, Right Angle, Wire-to-Board, 1 mm, 1 Rows, 4 Contacts, Surface Mount Right Angle, SH"
			(at 0 0 90)
			(layer "F.Fab")
			(hide yes)
			(effects
				(font
					(size 1.27 1.27)
					(thickness 0.15)
				)
			)
		)
		(property "Author" "Antmicro"
			(at 336.5255 -78.0255 0)
			(layer "F.Fab")
			(hide yes)
			(effects
				(font
					(size 1 1)
					(thickness 0.15)
				)
			)
		)
		(property "License" "Apache-2.0"
			(at 336.5255 -78.0255 0)
			(layer "F.Fab")
			(hide yes)
			(effects
				(font
					(size 1 1)
					(thickness 0.15)
				)
			)
		)
		(property "MPN" "SM04B-SRSS-TB(LF)(SN)"
			(at 336.5255 -78.0255 0)
			(layer "F.Fab")
			(hide yes)
			(effects
				(font
					(size 1 1)
					(thickness 0.15)
				)
			)
		)
		(property "Manufacturer" "JST Automotive Connectors"
			(at 336.5255 -78.0255 0)
			(layer "F.Fab")
			(hide yes)
			(effects
				(font
					(size 1 1)
					(thickness 0.15)
				)
			)
		)
		(sheetfile "environment-sensor.kicad_sch")
		(attr smd)
		(fp_line
			(start 3.2 -2)
			(end 3.2 0.6)
			(stroke
				(width 0.15)
				(type solid)
			)
			(layer "F.SilkS")
		)
		(fp_line
			(start 2 -2)
			(end 3.2 -2)
			(stroke
				(width 0.15)
				(type solid)
			)
			(layer "F.SilkS")
		)
		(fp_line
			(start -2 -2)
			(end -3.2 -2)
			(stroke
				(width 0.15)
				(type solid)
			)
			(layer "F.SilkS")
		)
		(fp_line
			(start -3.2 -2)
			(end -3.2 0.6)
			(stroke
				(width 0.15)
				(type solid)
			)
			(layer "F.SilkS")
		)
		(fp_line
			(start -2 2.6)
			(end 2 2.6)
			(stroke
				(width 0.15)
				(type solid)
			)
			(layer "F.SilkS")
		)
		(fp_circle
			(center -2.1 -2.5)
			(end -2.05 -2.5)
			(stroke
				(width 0.15)
				(type solid)
			)
			(fill yes)
			(layer "F.SilkS")
		)
		(fp_rect
			(start -3.65 -3.14)
			(end 3.65 2.9)
			(stroke
				(width 0.05)
				(type solid)
			)
			(fill no)
			(layer "F.CrtYd")
		)
		(fp_rect
			(start -3 -2.475)
			(end 3 2.475)
			(stroke
				(width 0.15)
				(type solid)
			)
			(fill no)
			(layer "F.Fab")
		)
		(pad "1" smd roundrect
			(at -1.5 -2.12 270)
			(size 0.6 1.55)
			(layers "F.Cu" "F.Mask" "F.Paste")
			(roundrect_rratio 0.25)
			(net 1 "GND")
			(pintype "passive")
		)
		(pad "2" smd roundrect
			(at -0.5 -2.12 270)
			(size 0.6 1.55)
			(layers "F.Cu" "F.Mask" "F.Paste")
			(roundrect_rratio 0.25)
			(net 2 "+3V3")
			(pintype "passive")
		)
		(pad "3" smd roundrect
			(at 0.5 -2.12 270)
			(size 0.6 1.55)
			(layers "F.Cu" "F.Mask" "F.Paste")
			(roundrect_rratio 0.25)
			(net 9 "I2C_1_SDA")
			(pintype "passive")
		)
		(pad "4" smd roundrect
			(at 1.5 -2.12 270)
			(size 0.6 1.55)
			(layers "F.Cu" "F.Mask" "F.Paste")
			(roundrect_rratio 0.25)
			(net 8 "I2C_1_SCL")
			(pintype "passive")
		)
		(pad "MP" smd roundrect
			(at -2.8 1.755 90)
			(size 1.2 1.8)
			(layers "F.Cu" "F.Mask" "F.Paste")
			(roundrect_rratio 0.25)
			(net 88 "unconnected-(J2-PadMP)")
			(pintype "passive+no_connect")
		)
		(pad "MP" smd roundrect
			(at 2.8 1.755 90)
			(size 1.2 1.8)
			(layers "F.Cu" "F.Mask" "F.Paste")
			(roundrect_rratio 0.25)
			(net 88 "unconnected-(J2-PadMP)")
			(pintype "passive+no_connect")
		)
	)
	(footprint "antmicro-footprints:C_0402_1005Metric"
		(layer "F.Cu")
		(at 190.3 138.415 -90)
		(descr "Capacitor SMD 0402")
		(tags "capacitor SMD 0402")
		(property "Reference" "C24"
			(at -15.769 8.2 90)
			(layer "B.SilkS")
			(effects
				(font
					(size 0.7 0.7)
					(thickness 0.15)
				)
				(justify right bottom mirror)
			)
		)
		(property "Value" "C_2u2_0402"
			(at 0 1.4 90)
			(layer "F.Fab")
			(effects
				(font
					(size 0.7 0.7)
					(thickness 0.15)
				)
				(justify right bottom)
			)
		)
		(property "Description" "SMD Multilayer Ceramic Capacitor, 2.2 µF, 10 V, 0402 [1005 Metric], ± 10%, X5R, C"
			(at 0 0 270)
			(layer "F.Fab")
			(hide yes)
			(effects
				(font
					(size 1.27 1.27)
					(thickness 0.15)
				)
			)
		)
		(property "Author" "Antmicro"
			(at 51.885 328.715 0)
			(layer "F.Fab")
			(hide yes)
			(effects
				(font
					(size 1 1)
					(thickness 0.15)
				)
			)
		)
		(property "Dielectric" ""
			(at 51.885 328.715 0)
			(layer "F.Fab")
			(hide yes)
			(effects
				(font
					(size 1 1)
					(thickness 0.15)
				)
			)
		)
		(property "License" "Apache-2.0"
			(at 51.885 328.715 0)
			(layer "F.Fab")
			(hide yes)
			(effects
				(font
					(size 1 1)
					(thickness 0.15)
				)
			)
		)
		(property "MPN" "C1005X5R1A225K050BC"
			(at 51.885 328.715 0)
			(layer "F.Fab")
			(hide yes)
			(effects
				(font
					(size 1 1)
					(thickness 0.15)
				)
			)
		)
		(property "Manufacturer" "TDK"
			(at 51.885 328.715 0)
			(layer "F.Fab")
			(hide yes)
			(effects
				(font
					(size 1 1)
					(thickness 0.15)
				)
			)
		)
		(property "Public" "False"
			(at 51.885 328.715 0)
			(layer "F.Fab")
			(hide yes)
			(effects
				(font
					(size 1 1)
					(thickness 0.15)
				)
			)
		)
		(property "Val" "2u2"
			(at 51.885 328.715 0)
			(layer "F.Fab")
			(hide yes)
			(effects
				(font
					(size 1 1)
					(thickness 0.15)
				)
			)
		)
		(property "Voltage" ""
			(at 51.885 328.715 0)
			(layer "F.Fab")
			(hide yes)
			(effects
				(font
					(size 1 1)
					(thickness 0.15)
				)
			)
		)
		(sheetfile "environment-sensor.kicad_sch")
		(attr smd)
		(fp_rect
			(start -0.925 -0.47)
			(end 0.925 0.47)
			(stroke
				(width 0.05)
				(type default)
			)
			(fill no)
			(layer "F.CrtYd")
		)
		(fp_line
			(start -0.494 0.248)
			(end -0.494 -0.25)
			(stroke
				(width 0.15)
				(type solid)
			)
			(layer "F.Fab")
		)
		(fp_line
			(start 0.504 0.248)
			(end -0.494 0.248)
			(stroke
				(width 0.15)
				(type solid)
			)
			(layer "F.Fab")
		)
		(fp_line
			(start -0.494 -0.25)
			(end 0.504 -0.25)
			(stroke
				(width 0.15)
				(type solid)
			)
			(layer "F.Fab")
		)
		(fp_line
			(start 0.504 -0.25)
			(end 0.504 0.248)
			(stroke
				(width 0.15)
				(type solid)
			)
			(layer "F.Fab")
		)
		(pad "1" smd roundrect
			(at -0.48 0 270)
			(size 0.59 0.64)
			(layers "F.Cu" "F.Mask" "F.Paste")
			(roundrect_rratio 0.25)
			(net 1 "GND")
			(pintype "passive")
		)
		(pad "2" smd roundrect
			(at 0.48 0 270)
			(size 0.59 0.64)
			(layers "F.Cu" "F.Mask" "F.Paste")
			(roundrect_rratio 0.25)
			(net 32 "Net-(U3-VREF+)")
			(pintype "passive")
		)
	)
	(footprint "antmicro-footprints:MP_Pad5.4mm_Drill2.7mm"
		(layer "F.Cu")
		(at 163.7 136.3)
		(descr "Mounting Hole 2.7mm, M2.5")
		(tags "mounting hole 2.7mm m2.5")
		(property "Reference" "MP2"
			(at -3.55 3.45 0)
			(layer "F.SilkS")
			(effects
				(font
					(size 0.7 0.7)
					(thickness 0.15)
				)
				(justify left bottom)
			)
		)
		(property "Value" "MP_Pad5.4mm_Drill2.7mm"
			(at 0 3.6 0)
			(layer "F.Fab")
			(effects
				(font
					(size 0.7 0.7)
					(thickness 0.15)
				)
				(justify left bottom)
			)
		)
		(property "Description" "Mechanical part"
			(at 0 0 0)
			(layer "F.Fab")
			(hide yes)
			(effects
				(font
					(size 1.27 1.27)
					(thickness 0.15)
				)
			)
		)
		(property "Author" "Antmicro"
			(at 0 0 0)
			(layer "F.Fab")
			(hide yes)
			(effects
				(font
					(size 1 1)
					(thickness 0.15)
				)
			)
		)
		(property "License" "Apache-2.0"
			(at 0 0 0)
			(layer "F.Fab")
			(hide yes)
			(effects
				(font
					(size 1 1)
					(thickness 0.15)
				)
			)
		)
		(property "Public" "False"
			(at 0 0 0)
			(layer "F.Fab")
			(hide yes)
			(effects
				(font
					(size 1 1)
					(thickness 0.15)
				)
			)
		)
		(sheetfile "environment-sensor.kicad_sch")
		(attr exclude_from_pos_files exclude_from_bom)
		(pad "1" thru_hole circle
			(at 0 0)
			(size 5.4 5.4)
			(drill 2.7)
			(layers "*.Cu" "*.Mask")
			(remove_unused_layers no)
			(net 23 "unconnected-(MP2-Pad1)")
			(pintype "passive+no_connect")
		)
	)
	(footprint "antmicro-footprints:C_0402_1005Metric"
		(layer "F.Cu")
		(at 189.754 117.597)
		(descr "Capacitor SMD 0402")
		(tags "capacitor SMD 0402")
		(property "Reference" "C18"
			(at 1.013 0.303 0)
			(layer "F.SilkS")
			(effects
				(font
					(size 0.7 0.7)
					(thickness 0.15)
				)
				(justify left bottom)
			)
		)
		(property "Value" "C_100n_0402"
			(at 0 1.4 0)
			(layer "F.Fab")
			(effects
				(font
					(size 0.7 0.7)
					(thickness 0.15)
				)
				(justify left bottom)
			)
		)
		(property "Description" "SMD Multilayer Ceramic Capacitor, 0.1 µF, 50 V, 0402 [1005 Metric], ± 10%, X5R, GRM Series"
			(at 0 0 0)
			(layer "F.Fab")
			(hide yes)
			(effects
				(font
					(size 1.27 1.27)
					(thickness 0.15)
				)
			)
		)
		(property "Author" "Antmicro"
			(at 0 0 0)
			(layer "F.Fab")
			(hide yes)
			(effects
				(font
					(size 1 1)
					(thickness 0.15)
				)
			)
		)
		(property "Dielectric" "X5R"
			(at 0 0 0)
			(layer "F.Fab")
			(hide yes)
			(effects
				(font
					(size 1 1)
					(thickness 0.15)
				)
			)
		)
		(property "License" "Apache-2.0"
			(at 0 0 0)
			(layer "F.Fab")
			(hide yes)
			(effects
				(font
					(size 1 1)
					(thickness 0.15)
				)
			)
		)
		(property "MPN" "GRM155R61H104KE14D"
			(at 0 0 0)
			(layer "F.Fab")
			(hide yes)
			(effects
				(font
					(size 1 1)
					(thickness 0.15)
				)
			)
		)
		(property "Manufacturer" "Murata"
			(at 0 0 0)
			(layer "F.Fab")
			(hide yes)
			(effects
				(font
					(size 1 1)
					(thickness 0.15)
				)
			)
		)
		(property "Public" "False"
			(at 0 0 0)
			(layer "F.Fab")
			(hide yes)
			(effects
				(font
					(size 1 1)
					(thickness 0.15)
				)
			)
		)
		(property "Val" "100n"
			(at 0 0 0)
			(layer "F.Fab")
			(hide yes)
			(effects
				(font
					(size 1 1)
					(thickness 0.15)
				)
			)
		)
		(property "Voltage" "50V"
			(at 0 0 0)
			(layer "F.Fab")
			(hide yes)
			(effects
				(font
					(size 1 1)
					(thickness 0.15)
				)
			)
		)
		(sheetfile "environment-sensor.kicad_sch")
		(attr smd)
		(fp_rect
			(start -0.925 -0.47)
			(end 0.925 0.47)
			(stroke
				(width 0.05)
				(type default)
			)
			(fill no)
			(layer "F.CrtYd")
		)
		(fp_line
			(start -0.494 -0.25)
			(end 0.504 -0.25)
			(stroke
				(width 0.15)
				(type solid)
			)
			(layer "F.Fab")
		)
		(fp_line
			(start -0.494 0.248)
			(end -0.494 -0.25)
			(stroke
				(width 0.15)
				(type solid)
			)
			(layer "F.Fab")
		)
		(fp_line
			(start 0.504 -0.25)
			(end 0.504 0.248)
			(stroke
				(width 0.15)
				(type solid)
			)
			(layer "F.Fab")
		)
		(fp_line
			(start 0.504 0.248)
			(end -0.494 0.248)
			(stroke
				(width 0.15)
				(type solid)
			)
			(layer "F.Fab")
		)
		(pad "1" smd roundrect
			(at -0.48 0)
			(size 0.59 0.64)
			(layers "F.Cu" "F.Mask" "F.Paste")
			(roundrect_rratio 0.25)
			(net 1 "GND")
			(pintype "passive")
		)
		(pad "2" smd roundrect
			(at 0.48 0)
			(size 0.59 0.64)
			(layers "F.Cu" "F.Mask" "F.Paste")
			(roundrect_rratio 0.25)
			(net 2 "+3V3")
			(pintype "passive")
		)
	)
	(footprint "antmicro-footprints:TP_SMD_1mm"
		(layer "F.Cu")
		(at 199 134.75)
		(property "Reference" "TP11"
			(at -3.25 -0.05 0)
			(layer "F.SilkS")
			(hide yes)
			(effects
				(font
					(size 0.7 0.7)
					(thickness 0.15)
				)
				(justify left bottom)
			)
		)
		(property "Value" "TP_1mm_SMD"
			(at 0 1.4 0)
			(layer "F.Fab")
			(effects
				(font
					(size 0.7 0.7)
					(thickness 0.15)
				)
				(justify left bottom)
			)
		)
		(property "Description" "Test point 1mm SMD"
			(at 0 0 0)
			(layer "F.Fab")
			(hide yes)
			(effects
				(font
					(size 1.27 1.27)
					(thickness 0.15)
				)
			)
		)
		(property "Author" "Antmicro"
			(at 0 0 0)
			(layer "F.Fab")
			(hide yes)
			(effects
				(font
					(size 1 1)
					(thickness 0.15)
				)
			)
		)
		(property "License" "Apache-2.0"
			(at 0 0 0)
			(layer "F.Fab")
			(hide yes)
			(effects
				(font
					(size 1 1)
					(thickness 0.15)
				)
			)
		)
		(property "MPN" ""
			(at 0 0 0)
			(layer "F.Fab")
			(hide yes)
			(effects
				(font
					(size 1 1)
					(thickness 0.15)
				)
			)
		)
		(property "Manufacturer" ""
			(at 0 0 0)
			(layer "F.Fab")
			(hide yes)
			(effects
				(font
					(size 1 1)
					(thickness 0.15)
				)
			)
		)
		(property "Public" "False"
			(at 0 0 0)
			(layer "F.Fab")
			(hide yes)
			(effects
				(font
					(size 1 1)
					(thickness 0.15)
				)
			)
		)
		(sheetfile "environment-sensor.kicad_sch")
		(attr exclude_from_pos_files)
		(pad "1" smd circle
			(at 0 0)
			(size 1 1)
			(layers "F.Cu" "F.Mask")
			(net 9 "I2C_1_SDA")
			(pinfunction "1")
			(pintype "passive")
		)
	)
	(footprint "antmicro-footprints:R_0402_1005Metric"
		(layer "F.Cu")
		(at 175.55 136.15 180)
		(descr "Resistor SMD 0402")
		(tags "resistor SMD 0402")
		(property "Reference" "R12"
			(at -25.25 -1.65 180)
			(layer "F.SilkS")
			(effects
				(font
					(size 0.7 0.7)
					(thickness 0.15)
				)
				(justify left bottom)
			)
		)
		(property "Value" "R_470R_0402"
			(at 0 1.4 180)
			(layer "F.Fab")
			(effects
				(font
					(size 0.7 0.7)
					(thickness 0.15)
				)
				(justify left bottom)
			)
		)
		(property "Description" "SMD Chip Resistor, 470 ohm, ± 1%, 62.5 mW, 0402 [1005 Metric], Thick Film, General Purpose"
			(at 0 0 180)
			(layer "F.Fab")
			(hide yes)
			(effects
				(font
					(size 1.27 1.27)
					(thickness 0.15)
				)
			)
		)
		(property "Author" "Antmicro"
			(at 351.1 272.3 0)
			(layer "F.Fab")
			(hide yes)
			(effects
				(font
					(size 1 1)
					(thickness 0.15)
				)
			)
		)
		(property "License" "Apache-2.0"
			(at 351.1 272.3 0)
			(layer "F.Fab")
			(hide yes)
			(effects
				(font
					(size 1 1)
					(thickness 0.15)
				)
			)
		)
		(property "MPN" "CR0402-FX-4700GLF"
			(at 351.1 272.3 0)
			(layer "F.Fab")
			(hide yes)
			(effects
				(font
					(size 1 1)
					(thickness 0.15)
				)
			)
		)
		(property "Manufacturer" "Bourns"
			(at 351.1 272.3 0)
			(layer "F.Fab")
			(hide yes)
			(effects
				(font
					(size 1 1)
					(thickness 0.15)
				)
			)
		)
		(property "Public" "False"
			(at 351.1 272.3 0)
			(layer "F.Fab")
			(hide yes)
			(effects
				(font
					(size 1 1)
					(thickness 0.15)
				)
			)
		)
		(property "Tolerance" "1%"
			(at 351.1 272.3 0)
			(layer "F.Fab")
			(hide yes)
			(effects
				(font
					(size 1 1)
					(thickness 0.15)
				)
			)
		)
		(property "Val" "470R"
			(at 351.1 272.3 0)
			(layer "F.Fab")
			(hide yes)
			(effects
				(font
					(size 1 1)
					(thickness 0.15)
				)
			)
		)
		(sheetfile "environment-sensor.kicad_sch")
		(attr smd)
		(fp_rect
			(start -0.925 -0.47)
			(end 0.925 0.47)
			(stroke
				(width 0.05)
				(type default)
			)
			(fill no)
			(layer "F.CrtYd")
		)
		(fp_rect
			(start -0.5 -0.25)
			(end 0.5 0.25)
			(stroke
				(width 0.15)
				(type solid)
			)
			(fill no)
			(layer "F.Fab")
		)
		(pad "1" smd roundrect
			(at -0.48 0 180)
			(size 0.59 0.64)
			(layers "F.Cu" "F.Mask" "F.Paste")
			(roundrect_rratio 0.25)
			(net 1 "GND")
			(pintype "passive")
		)
		(pad "2" smd roundrect
			(at 0.48 0 180)
			(size 0.59 0.64)
			(layers "F.Cu" "F.Mask" "F.Paste")
			(roundrect_rratio 0.25)
			(net 10 "Net-(LD1-A)")
			(pintype "passive")
		)
	)
	(footprint "antmicro-footprints:R_0402_1005Metric"
		(layer "F.Cu")
		(at 182.75 126.25 -90)
		(descr "Resistor SMD 0402")
		(tags "resistor SMD 0402")
		(property "Reference" "R5"
			(at -11.75 -1.05 90)
			(layer "B.SilkS")
			(effects
				(font
					(size 0.7 0.7)
					(thickness 0.15)
				)
				(justify left bottom mirror)
			)
		)
		(property "Value" "R_0R_0402"
			(at 0 1.4 90)
			(layer "F.Fab")
			(effects
				(font
					(size 0.7 0.7)
					(thickness 0.15)
				)
				(justify right bottom)
			)
		)
		(property "Description" "SMD Chip Resistor, Jumper, 0 ohm, 100 mW, 0402 [1005 Metric], Thick Film, General Purpose"
			(at 0 0 270)
			(layer "F.Fab")
			(hide yes)
			(effects
				(font
					(size 1.27 1.27)
					(thickness 0.15)
				)
			)
		)
		(property "Author" "Antmicro"
			(at 56.5 309 0)
			(layer "F.Fab")
			(hide yes)
			(effects
				(font
					(size 1 1)
					(thickness 0.15)
				)
			)
		)
		(property "Current" "1A"
			(at 56.5 309 0)
			(layer "F.Fab")
			(hide yes)
			(effects
				(font
					(size 1 1)
					(thickness 0.15)
				)
			)
		)
		(property "License" "Apache-2.0"
			(at 56.5 309 0)
			(layer "F.Fab")
			(hide yes)
			(effects
				(font
					(size 1 1)
					(thickness 0.15)
				)
			)
		)
		(property "MPN" "ERJ2GE0R00X"
			(at 56.5 309 0)
			(layer "F.Fab")
			(hide yes)
			(effects
				(font
					(size 1 1)
					(thickness 0.15)
				)
			)
		)
		(property "Manufacturer" "Panasonic"
			(at 56.5 309 0)
			(layer "F.Fab")
			(hide yes)
			(effects
				(font
					(size 1 1)
					(thickness 0.15)
				)
			)
		)
		(property "Public" "False"
			(at 56.5 309 0)
			(layer "F.Fab")
			(hide yes)
			(effects
				(font
					(size 1 1)
					(thickness 0.15)
				)
			)
		)
		(property "Tolerance" ""
			(at 56.5 309 0)
			(layer "F.Fab")
			(hide yes)
			(effects
				(font
					(size 1 1)
					(thickness 0.15)
				)
			)
		)
		(property "Val" "0R"
			(at 56.5 309 0)
			(layer "F.Fab")
			(hide yes)
			(effects
				(font
					(size 1 1)
					(thickness 0.15)
				)
			)
		)
		(sheetfile "environment-sensor.kicad_sch")
		(attr smd)
		(fp_rect
			(start -0.925 -0.47)
			(end 0.925 0.47)
			(stroke
				(width 0.05)
				(type default)
			)
			(fill no)
			(layer "F.CrtYd")
		)
		(fp_rect
			(start -0.5 -0.25)
			(end 0.5 0.25)
			(stroke
				(width 0.15)
				(type solid)
			)
			(fill no)
			(layer "F.Fab")
		)
		(pad "1" smd roundrect
			(at -0.48 0 270)
			(size 0.59 0.64)
			(layers "F.Cu" "F.Mask" "F.Paste")
			(roundrect_rratio 0.25)
			(net 37 "Net-(U1-DTR#)")
			(pintype "passive")
		)
		(pad "2" smd roundrect
			(at 0.48 0 270)
			(size 0.59 0.64)
			(layers "F.Cu" "F.Mask" "F.Paste")
			(roundrect_rratio 0.25)
			(net 20 "SWDIO-JTMS")
			(pintype "passive")
		)
	)
)
